# T6G (Grand Teton) — schematic netlist excerpt (pin names and nets, part order shuffled) for the footprints in the layout excerpt that follows; sources: Cadence DE-HDL packaged netlist, KiCad conversion of 04192023_DAF0TMB3IC0_F0TG_MB_C_brd_V02_OCP.brd

PR345  Q_RES  2.2 1% CHIP  pkg 0402LF  page 195 : A = PVDDCR_CPU0_P0_PVCC ; B = PVDDCR_CPU0_P0_VCC4
PC191_4  Q_CAP  22UF 4V 20% X6S  pkg C0805  page 206 : A = PVDDIO_P0 ; B = GND
PC8001  Q_CAP  22UF 16V 20% X6S  pkg C0805  page 192 : A = SW_P12V_AUX_PVDD_33_S5_FLT ; B = GND

(kicad_pcb
	(version 20260206)
	(generator "pcbnew")
	(generator_version "10.0")
	(general
		(thickness 1.6)
		(legacy_teardrops no)
	)
	(paper "A4")
	(title_block
		(title "04192023_DAF0TMB3IC0_F0TG_MB_C_brd_V02_OCP.brd")
		(comment 1 "Grand Teton / footprints 6271-6273 of 8354")
	)
	(layers
		(0 "F.Cu" signal "TOP")
		(4 "In1.Cu" signal "GND")
		(6 "In2.Cu" signal "IN1")
		(8 "In3.Cu" signal "GND1")
		(10 "In4.Cu" signal "IN2")
		(12 "In5.Cu" signal "GND2")
		(14 "In6.Cu" signal "IN3")
		(16 "In7.Cu" signal "GND3")
		(18 "In8.Cu" signal "VCC")
		(20 "In9.Cu" signal "VCC1")
		(22 "In10.Cu" signal "GND4")
		(24 "In11.Cu" signal "IN4")
		(26 "In12.Cu" signal "GND5")
		(28 "In13.Cu" signal "IN5")
		(30 "In14.Cu" signal "GND6")
		(32 "In15.Cu" signal "IN6")
		(34 "In16.Cu" signal "GND7")
		(2 "B.Cu" signal "BOTTOM")
		(9 "F.Adhes" user "F.Adhesive")
		(11 "B.Adhes" user "B.Adhesive")
		(13 "F.Paste" user "Package Geometry/Pastemask Top")
		(15 "B.Paste" user "Package Geometry/Pastemask Bottom")
		(5 "F.SilkS" user "Ref Des/Silkscreen Top")
		(7 "B.SilkS" user "Ref Des/Silkscreen Bottom")
		(1 "F.Mask" user "Board Geometry/Soldermask Top")
		(3 "B.Mask" user "Board Geometry/Soldermask Bottom")
		(17 "Dwgs.User" user "User.Drawings")
		(19 "Cmts.User" user "User.Comments")
		(21 "Eco1.User" user "User.Eco1")
		(23 "Eco2.User" user "User.Eco2")
		(25 "Edge.Cuts" user "Board Geometry/Outline")
		(27 "Margin" user)
		(31 "F.CrtYd" user "Package Geometry/Place Bound Top")
		(29 "B.CrtYd" user "Package Geometry/Place Bound Bottom")
		(35 "F.Fab" user "Ref Des/Assembly Top")
		(33 "B.Fab" user "Ref Des/Assembly Bottom")
	)
	(footprint ""
		(layer "B.Cu")
		(at 199.941942 -344.270584)
		(property "Reference" "PC8001"
			(at 0 0 0)
			(layer "B.SilkS")
			(hide yes)
			(effects
				(font
					(size 1.27 1.27)
				)
				(justify mirror)
			)
		)
		(property "Value" ""
			(at 0 0 0)
			(layer "B.Fab")
			(effects
				(font
					(size 1.27 1.27)
				)
				(justify mirror)
			)
		)
		(duplicate_pad_numbers_are_jumpers no)
		(fp_line
			(start -1.524 -0.762)
			(end -1.524 0.762)
			(stroke
				(width 0.1524)
				(type default)
			)
			(layer "B.SilkS")
		)
		(fp_line
			(start -1.524 0.762)
			(end 1.524 0.762)
			(stroke
				(width 0.1524)
				(type default)
			)
			(layer "B.SilkS")
		)
		(fp_line
			(start 1.524 -0.762)
			(end -1.524 -0.762)
			(stroke
				(width 0.1524)
				(type default)
			)
			(layer "B.SilkS")
		)
		(fp_line
			(start 1.524 0.762)
			(end 1.524 -0.762)
			(stroke
				(width 0.1524)
				(type default)
			)
			(layer "B.SilkS")
		)
		(fp_line
			(start -1.1049 -0.724916)
			(end 1.1049 -0.724916)
			(stroke
				(width 0.1)
				(type default)
			)
			(layer "B.Fab")
		)
		(fp_line
			(start -1.1049 0.724916)
			(end -1.1049 -0.724916)
			(stroke
				(width 0.1)
				(type default)
			)
			(layer "B.Fab")
		)
		(fp_line
			(start 1.1049 -0.724916)
			(end 1.1049 0.724916)
			(stroke
				(width 0.1)
				(type default)
			)
			(layer "B.Fab")
		)
		(fp_line
			(start 1.1049 0.724916)
			(end -1.1049 0.724916)
			(stroke
				(width 0.1)
				(type default)
			)
			(layer "B.Fab")
		)
		(pad "1" smd rect
			(at 0.889 0)
			(size 1.016 1.27)
			(layers "B.Cu" "B.Mask" "B.Paste")
			(net "SW_P12V_AUX_PVDD_33_S5_FLT")
		)
		(pad "2" smd rect
			(at -0.889 0)
			(size 1.016 1.27)
			(layers "B.Cu" "B.Mask" "B.Paste")
			(net "GND")
		)
	)
	(footprint ""
		(layer "B.Cu")
		(at 391.72007 -181.684676 90)
		(property "Reference" "PR345"
			(at 0 0 90)
			(layer "B.SilkS")
			(hide yes)
			(effects
				(font
					(size 1.27 1.27)
				)
				(justify mirror)
			)
		)
		(property "Value" ""
			(at 0 0 90)
			(layer "B.Fab")
			(effects
				(font
					(size 1.27 1.27)
				)
				(justify mirror)
			)
		)
		(duplicate_pad_numbers_are_jumpers no)
		(fp_line
			(start 0.7874 -0.4064)
			(end -0.7874 -0.4064)
			(stroke
				(width 0.1524)
				(type default)
			)
			(layer "B.SilkS")
		)
		(fp_line
			(start -0.7874 -0.4064)
			(end -0.7874 0.4064)
			(stroke
				(width 0.1524)
				(type default)
			)
			(layer "B.SilkS")
		)
		(fp_line
			(start 0.7874 0.4064)
			(end 0.7874 -0.4064)
			(stroke
				(width 0.1524)
				(type default)
			)
			(layer "B.SilkS")
		)
		(fp_line
			(start -0.7874 0.4064)
			(end 0.7874 0.4064)
			(stroke
				(width 0.1524)
				(type default)
			)
			(layer "B.SilkS")
		)
		(fp_line
			(start 0.67945 -0.305054)
			(end 0.12065 -0.305054)
			(stroke
				(width 0.1)
				(type default)
			)
			(layer "B.Fab")
		)
		(fp_line
			(start 0.12065 -0.305054)
			(end 0.12065 -0.2794)
			(stroke
				(width 0.1)
				(type default)
			)
			(layer "B.Fab")
		)
		(fp_line
			(start -0.12065 -0.3048)
			(end -0.67945 -0.3048)
			(stroke
				(width 0.1)
				(type default)
			)
			(layer "B.Fab")
		)
		(fp_line
			(start -0.67945 -0.3048)
			(end -0.67945 0.3048)
			(stroke
				(width 0.1)
				(type default)
			)
			(layer "B.Fab")
		)
		(fp_line
			(start 0.12065 -0.2794)
			(end -0.12065 -0.2794)
			(stroke
				(width 0.1)
				(type default)
			)
			(layer "B.Fab")
		)
		(fp_line
			(start -0.12065 -0.2794)
			(end -0.12065 -0.3048)
			(stroke
				(width 0.1)
				(type default)
			)
			(layer "B.Fab")
		)
		(fp_line
			(start 0.12065 0.2794)
			(end 0.12065 0.3048)
			(stroke
				(width 0.1)
				(type default)
			)
			(layer "B.Fab")
		)
		(fp_line
			(start -0.120396 0.2794)
			(end 0.12065 0.2794)
			(stroke
				(width 0.1)
				(type default)
			)
			(layer "B.Fab")
		)
		(fp_line
			(start 0.67945 0.3048)
			(end 0.67945 -0.305054)
			(stroke
				(width 0.1)
				(type default)
			)
			(layer "B.Fab")
		)
		(fp_line
			(start 0.12065 0.3048)
			(end 0.67945 0.3048)
			(stroke
				(width 0.1)
				(type default)
			)
			(layer "B.Fab")
		)
		(fp_line
			(start -0.120396 0.3048)
			(end -0.120396 0.2794)
			(stroke
				(width 0.1)
				(type default)
			)
			(layer "B.Fab")
		)
		(fp_line
			(start -0.67945 0.3048)
			(end -0.120396 0.3048)
			(stroke
				(width 0.1)
				(type default)
			)
			(layer "B.Fab")
		)
		(pad "1" smd circle
			(at 0.40005 0 270)
			(size 0 0)
			(layers "B.Cu" "B.Mask" "B.Paste")
			(net "PVDDCR_CPU0_P0_PVCC")
		)
		(pad "2" smd circle
			(at -0.40005 0 270)
			(size 0 0)
			(layers "B.Cu" "B.Mask" "B.Paste")
			(net "PVDDCR_CPU0_P0_VCC4")
		)
	)
	(footprint ""
		(layer "B.Cu")
		(at 271.711928 -337.980528 -90)
		(property "Reference" "PC191_4"
			(at 0 0 90)
			(layer "B.SilkS")
			(hide yes)
			(effects
				(font
					(size 1.27 1.27)
				)
				(justify mirror)
			)
		)
		(property "Value" ""
			(at 0 0 90)
			(layer "B.Fab")
			(effects
				(font
					(size 1.27 1.27)
				)
				(justify mirror)
			)
		)
		(duplicate_pad_numbers_are_jumpers no)
		(fp_line
			(start -1.524 0.762)
			(end 1.524 0.762)
			(stroke
				(width 0.1524)
				(type default)
			)
			(layer "B.SilkS")
		)
		(fp_line
			(start 1.524 0.762)
			(end 1.524 -0.762)
			(stroke
				(width 0.1524)
				(type default)
			)
			(layer "B.SilkS")
		)
		(fp_line
			(start -1.524 -0.762)
			(end -1.524 0.762)
			(stroke
				(width 0.1524)
				(type default)
			)
			(layer "B.SilkS")
		)
		(fp_line
			(start 1.524 -0.762)
			(end -1.524 -0.762)
			(stroke
				(width 0.1524)
				(type default)
			)
			(layer "B.SilkS")
		)
		(fp_line
			(start -1.1049 0.724916)
			(end -1.1049 -0.724916)
			(stroke
				(width 0.1)
				(type default)
			)
			(layer "B.Fab")
		)
		(fp_line
			(start 1.1049 0.724916)
			(end -1.1049 0.724916)
			(stroke
				(width 0.1)
				(type default)
			)
			(layer "B.Fab")
		)
		(fp_line
			(start -1.1049 -0.724916)
			(end 1.1049 -0.724916)
			(stroke
				(width 0.1)
				(type default)
			)
			(layer "B.Fab")
		)
		(fp_line
			(start 1.1049 -0.724916)
			(end 1.1049 0.724916)
			(stroke
				(width 0.1)
				(type default)
			)
			(layer "B.Fab")
		)
		(pad "1" smd rect
			(at 0.889 0 270)
			(size 1.016 1.27)
			(layers "B.Cu" "B.Mask" "B.Paste")
			(net "PVDDIO_P0")
		)
		(pad "2" smd rect
			(at -0.889 0 270)
			(size 1.016 1.27)
			(layers "B.Cu" "B.Mask" "B.Paste")
			(net "GND")
		)
	)
)
